(kicad_pcb
	(version 20260206)
	(generator "pcbnew")
	(generator_version "10.0")
	(general
		(thickness 1.6)
		(legacy_teardrops no)
	)
	(paper "A4")
	(title_block
		(title "01162023_DA0F0TEBIF0_F0T_Expander_BD_F_brd_V02_OCP.brd")
		(comment 1 "Grand Teton / footprints 5747-5753 of 9728")
	)
	(layers
		(0 "F.Cu" signal "TOP")
		(4 "In1.Cu" signal "GND")
		(6 "In2.Cu" signal "VCC")
		(8 "In3.Cu" signal "VCC1")
		(10 "In4.Cu" signal "GND1")
		(12 "In5.Cu" signal "IN1")
		(14 "In6.Cu" signal "GND2")
		(16 "In7.Cu" signal "IN2")
		(18 "In8.Cu" signal "GND3")
		(20 "In9.Cu" signal "IN3")
		(22 "In10.Cu" signal "GND4")
		(24 "In11.Cu" signal "IN4")
		(26 "In12.Cu" signal "GND5")
		(28 "In13.Cu" signal "IN5")
		(30 "In14.Cu" signal "GND6")
		(32 "In15.Cu" signal "IN6")
		(34 "In16.Cu" signal "GND7")
		(2 "B.Cu" signal "BOTTOM")
		(9 "F.Adhes" user "F.Adhesive")
		(11 "B.Adhes" user "B.Adhesive")
		(13 "F.Paste" user "Package Geometry/Pastemask Top")
		(15 "B.Paste" user "Package Geometry/Pastemask Bottom")
		(5 "F.SilkS" user "Ref Des/Silkscreen Top")
		(7 "B.SilkS" user "Ref Des/Silkscreen Bottom")
		(1 "F.Mask" user "Board Geometry/Soldermask Top")
		(3 "B.Mask" user "Board Geometry/Soldermask Bottom")
		(17 "Dwgs.User" user "User.Drawings")
		(19 "Cmts.User" user "User.Comments")
		(21 "Eco1.User" user "User.Eco1")
		(23 "Eco2.User" user "User.Eco2")
		(25 "Edge.Cuts" user "Board Geometry/Outline")
		(27 "Margin" user)
		(31 "F.CrtYd" user "Package Geometry/Place Bound Top")
		(29 "B.CrtYd" user "Package Geometry/Place Bound Bottom")
		(35 "F.Fab" user "Ref Des/Assembly Top")
		(33 "B.Fab" user "Ref Des/Assembly Bottom")
	)
	(footprint ""
		(layer "F.Cu")
		(at 294.70985 -165.670484 -90)
		(property "Reference" "R2468"
			(at 0 0 270)
			(layer "F.SilkS")
			(hide yes)
			(effects
				(font
					(size 1.27 1.27)
				)
			)
		)
		(property "Value" ""
			(at 0 0 270)
			(layer "F.Fab")
			(effects
				(font
					(size 1.27 1.27)
				)
			)
		)
		(duplicate_pad_numbers_are_jumpers no)
		(fp_line
			(start -0.7874 0.4064)
			(end -0.7874 -0.4064)
			(stroke
				(width 0.1524)
				(type default)
			)
			(layer "F.SilkS")
		)
		(fp_line
			(start 0.7874 0.4064)
			(end -0.7874 0.4064)
			(stroke
				(width 0.1524)
				(type default)
			)
			(layer "F.SilkS")
		)
		(fp_line
			(start -0.7874 -0.4064)
			(end 0.7874 -0.4064)
			(stroke
				(width 0.1524)
				(type default)
			)
			(layer "F.SilkS")
		)
		(fp_line
			(start 0.7874 -0.4064)
			(end 0.7874 0.4064)
			(stroke
				(width 0.1524)
				(type default)
			)
			(layer "F.SilkS")
		)
		(fp_line
			(start -0.67945 0.3048)
			(end -0.67945 -0.305054)
			(stroke
				(width 0.1)
				(type default)
			)
			(layer "F.Fab")
		)
		(fp_line
			(start -0.12065 0.3048)
			(end -0.67945 0.3048)
			(stroke
				(width 0.1)
				(type default)
			)
			(layer "F.Fab")
		)
		(fp_line
			(start 0.120396 0.3048)
			(end 0.120396 0.2794)
			(stroke
				(width 0.1)
				(type default)
			)
			(layer "F.Fab")
		)
		(fp_line
			(start 0.67945 0.3048)
			(end 0.120396 0.3048)
			(stroke
				(width 0.1)
				(type default)
			)
			(layer "F.Fab")
		)
		(fp_line
			(start -0.12065 0.2794)
			(end -0.12065 0.3048)
			(stroke
				(width 0.1)
				(type default)
			)
			(layer "F.Fab")
		)
		(fp_line
			(start 0.120396 0.2794)
			(end -0.12065 0.2794)
			(stroke
				(width 0.1)
				(type default)
			)
			(layer "F.Fab")
		)
		(fp_line
			(start -0.12065 -0.2794)
			(end 0.12065 -0.2794)
			(stroke
				(width 0.1)
				(type default)
			)
			(layer "F.Fab")
		)
		(fp_line
			(start 0.12065 -0.2794)
			(end 0.12065 -0.3048)
			(stroke
				(width 0.1)
				(type default)
			)
			(layer "F.Fab")
		)
		(fp_line
			(start 0.12065 -0.3048)
			(end 0.67945 -0.3048)
			(stroke
				(width 0.1)
				(type default)
			)
			(layer "F.Fab")
		)
		(fp_line
			(start 0.67945 -0.3048)
			(end 0.67945 0.3048)
			(stroke
				(width 0.1)
				(type default)
			)
			(layer "F.Fab")
		)
		(fp_line
			(start -0.67945 -0.305054)
			(end -0.12065 -0.305054)
			(stroke
				(width 0.1)
				(type default)
			)
			(layer "F.Fab")
		)
		(fp_line
			(start -0.12065 -0.305054)
			(end -0.12065 -0.2794)
			(stroke
				(width 0.1)
				(type default)
			)
			(layer "F.Fab")
		)
		(pad "1" smd circle
			(at -0.40005 0 270)
			(size 0 0)
			(layers "F.Cu" "F.Mask" "F.Paste")
			(net "NIC4_PWRBRK_R_N")
		)
		(pad "2" smd circle
			(at 0.40005 0 270)
			(size 0 0)
			(layers "F.Cu" "F.Mask" "F.Paste")
			(net "NIC4_PWRBRK_N")
		)
	)
	(footprint ""
		(layer "F.Cu")
		(at 324.991222 -235.075222 90)
		(property "Reference" "R4388"
			(at 0 0 90)
			(layer "F.SilkS")
			(hide yes)
			(effects
				(font
					(size 1.27 1.27)
				)
			)
		)
		(property "Value" ""
			(at 0 0 90)
			(layer "F.Fab")
			(effects
				(font
					(size 1.27 1.27)
				)
			)
		)
		(duplicate_pad_numbers_are_jumpers no)
		(fp_line
			(start 0.7874 -0.4064)
			(end 0.7874 0.4064)
			(stroke
				(width 0.1524)
				(type default)
			)
			(layer "F.SilkS")
		)
		(fp_line
			(start -0.7874 -0.4064)
			(end 0.7874 -0.4064)
			(stroke
				(width 0.1524)
				(type default)
			)
			(layer "F.SilkS")
		)
		(fp_line
			(start 0.7874 0.4064)
			(end -0.7874 0.4064)
			(stroke
				(width 0.1524)
				(type default)
			)
			(layer "F.SilkS")
		)
		(fp_line
			(start -0.7874 0.4064)
			(end -0.7874 -0.4064)
			(stroke
				(width 0.1524)
				(type default)
			)
			(layer "F.SilkS")
		)
		(fp_line
			(start -0.12065 -0.305054)
			(end -0.12065 -0.2794)
			(stroke
				(width 0.1)
				(type default)
			)
			(layer "F.Fab")
		)
		(fp_line
			(start -0.67945 -0.305054)
			(end -0.12065 -0.305054)
			(stroke
				(width 0.1)
				(type default)
			)
			(layer "F.Fab")
		)
		(fp_line
			(start 0.67945 -0.3048)
			(end 0.67945 0.3048)
			(stroke
				(width 0.1)
				(type default)
			)
			(layer "F.Fab")
		)
		(fp_line
			(start 0.12065 -0.3048)
			(end 0.67945 -0.3048)
			(stroke
				(width 0.1)
				(type default)
			)
			(layer "F.Fab")
		)
		(fp_line
			(start 0.12065 -0.2794)
			(end 0.12065 -0.3048)
			(stroke
				(width 0.1)
				(type default)
			)
			(layer "F.Fab")
		)
		(fp_line
			(start -0.12065 -0.2794)
			(end 0.12065 -0.2794)
			(stroke
				(width 0.1)
				(type default)
			)
			(layer "F.Fab")
		)
		(fp_line
			(start 0.120396 0.2794)
			(end -0.12065 0.2794)
			(stroke
				(width 0.1)
				(type default)
			)
			(layer "F.Fab")
		)
		(fp_line
			(start -0.12065 0.2794)
			(end -0.12065 0.3048)
			(stroke
				(width 0.1)
				(type default)
			)
			(layer "F.Fab")
		)
		(fp_line
			(start 0.67945 0.3048)
			(end 0.120396 0.3048)
			(stroke
				(width 0.1)
				(type default)
			)
			(layer "F.Fab")
		)
		(fp_line
			(start 0.120396 0.3048)
			(end 0.120396 0.2794)
			(stroke
				(width 0.1)
				(type default)
			)
			(layer "F.Fab")
		)
		(fp_line
			(start -0.12065 0.3048)
			(end -0.67945 0.3048)
			(stroke
				(width 0.1)
				(type default)
			)
			(layer "F.Fab")
		)
		(fp_line
			(start -0.67945 0.3048)
			(end -0.67945 -0.305054)
			(stroke
				(width 0.1)
				(type default)
			)
			(layer "F.Fab")
		)
		(pad "1" smd circle
			(at -0.40005 0 90)
			(size 0 0)
			(layers "F.Cu" "F.Mask" "F.Paste")
			(net "RST_PEX_SYS_BUF_R_N")
		)
		(pad "2" smd circle
			(at 0.40005 0 90)
			(size 0 0)
			(layers "F.Cu" "F.Mask" "F.Paste")
			(net "RST_PEX1_SYS_N")
		)
	)
	(footprint ""
		(layer "F.Cu")
		(at 338.64169 -293.5351 90)
		(property "Reference" "PL12"
			(at -4.920234 28.63723 90)
			(unlocked yes)
			(layer "F.SilkS")
			(effects
				(font
					(size 0.7874 0.5842)
					(thickness 0.1524)
				)
				(justify left)
			)
		)
		(property "Value" ""
			(at 0 0 90)
			(layer "F.Fab")
			(effects
				(font
					(size 1.27 1.27)
				)
			)
		)
		(duplicate_pad_numbers_are_jumpers no)
		(fp_line
			(start 4.800092 -3.199892)
			(end 4.800092 -1.6764)
			(stroke
				(width 0.1524)
				(type default)
			)
			(layer "F.SilkS")
		)
		(fp_line
			(start -4.800092 -3.199892)
			(end 4.800092 -3.199892)
			(stroke
				(width 0.1524)
				(type default)
			)
			(layer "F.SilkS")
		)
		(fp_line
			(start -4.800092 -1.6764)
			(end -4.800092 -3.199892)
			(stroke
				(width 0.1524)
				(type default)
			)
			(layer "F.SilkS")
		)
		(fp_line
			(start 4.800092 1.6764)
			(end 4.800092 3.199892)
			(stroke
				(width 0.1524)
				(type default)
			)
			(layer "F.SilkS")
		)
		(fp_line
			(start 4.800092 3.199892)
			(end -4.800092 3.199892)
			(stroke
				(width 0.1524)
				(type default)
			)
			(layer "F.SilkS")
		)
		(fp_line
			(start -4.800092 3.199892)
			(end -4.800092 1.6764)
			(stroke
				(width 0.1524)
				(type default)
			)
			(layer "F.SilkS")
		)
		(fp_line
			(start 4.800092 -3.199892)
			(end 4.800092 3.199892)
			(stroke
				(width 0.1)
				(type default)
			)
			(layer "F.Fab")
		)
		(fp_line
			(start -4.800092 -3.199892)
			(end 4.800092 -3.199892)
			(stroke
				(width 0.1)
				(type default)
			)
			(layer "F.Fab")
		)
		(fp_line
			(start 4.800092 3.199892)
			(end -4.800092 3.199892)
			(stroke
				(width 0.1)
				(type default)
			)
			(layer "F.Fab")
		)
		(fp_line
			(start -4.800092 3.199892)
			(end -4.800092 -3.199892)
			(stroke
				(width 0.1)
				(type default)
			)
			(layer "F.Fab")
		)
		(pad "1" smd rect
			(at -3.074924 0 180)
			(size 3.0988 3.3528)
			(layers "F.Cu" "F.Mask" "F.Paste")
			(net "SW_P0V8_PEX2_PH1")
		)
		(pad "2" smd rect
			(at 3.074924 0 180)
			(size 3.0988 3.3528)
			(layers "F.Cu" "F.Mask" "F.Paste")
			(net "P0V8_PEX2")
		)
	)
	(footprint ""
		(layer "F.Cu")
		(at 253.147322 -21.37156)
		(property "Reference" "C3929"
			(at 0 0 0)
			(layer "F.SilkS")
			(hide yes)
			(effects
				(font
					(size 1.27 1.27)
				)
			)
		)
		(property "Value" ""
			(at 0 0 0)
			(layer "F.Fab")
			(effects
				(font
					(size 1.27 1.27)
				)
			)
		)
		(duplicate_pad_numbers_are_jumpers no)
		(fp_line
			(start -0.7874 -0.4064)
			(end 0.7874 -0.4064)
			(stroke
				(width 0.1524)
				(type default)
			)
			(layer "F.SilkS")
		)
		(fp_line
			(start -0.7874 0.4064)
			(end -0.7874 -0.4064)
			(stroke
				(width 0.1524)
				(type default)
			)
			(layer "F.SilkS")
		)
		(fp_line
			(start 0.7874 -0.4064)
			(end 0.7874 0.4064)
			(stroke
				(width 0.1524)
				(type default)
			)
			(layer "F.SilkS")
		)
		(fp_line
			(start 0.7874 0.4064)
			(end -0.7874 0.4064)
			(stroke
				(width 0.1524)
				(type default)
			)
			(layer "F.SilkS")
		)
		(fp_line
			(start -0.67945 -0.305054)
			(end -0.12065 -0.305054)
			(stroke
				(width 0.1)
				(type default)
			)
			(layer "F.Fab")
		)
		(fp_line
			(start -0.67945 0.3048)
			(end -0.67945 -0.305054)
			(stroke
				(width 0.1)
				(type default)
			)
			(layer "F.Fab")
		)
		(fp_line
			(start -0.12065 -0.305054)
			(end -0.12065 -0.2794)
			(stroke
				(width 0.1)
				(type default)
			)
			(layer "F.Fab")
		)
		(fp_line
			(start -0.12065 -0.2794)
			(end 0.12065 -0.2794)
			(stroke
				(width 0.1)
				(type default)
			)
			(layer "F.Fab")
		)
		(fp_line
			(start -0.12065 0.2794)
			(end -0.12065 0.3048)
			(stroke
				(width 0.1)
				(type default)
			)
			(layer "F.Fab")
		)
		(fp_line
			(start -0.12065 0.3048)
			(end -0.67945 0.3048)
			(stroke
				(width 0.1)
				(type default)
			)
			(layer "F.Fab")
		)
		(fp_line
			(start 0.120396 0.2794)
			(end -0.12065 0.2794)
			(stroke
				(width 0.1)
				(type default)
			)
			(layer "F.Fab")
		)
		(fp_line
			(start 0.120396 0.3048)
			(end 0.120396 0.2794)
			(stroke
				(width 0.1)
				(type default)
			)
			(layer "F.Fab")
		)
		(fp_line
			(start 0.12065 -0.3048)
			(end 0.67945 -0.3048)
			(stroke
				(width 0.1)
				(type default)
			)
			(layer "F.Fab")
		)
		(fp_line
			(start 0.12065 -0.2794)
			(end 0.12065 -0.3048)
			(stroke
				(width 0.1)
				(type default)
			)
			(layer "F.Fab")
		)
		(fp_line
			(start 0.67945 -0.3048)
			(end 0.67945 0.3048)
			(stroke
				(width 0.1)
				(type default)
			)
			(layer "F.Fab")
		)
		(fp_line
			(start 0.67945 0.3048)
			(end 0.120396 0.3048)
			(stroke
				(width 0.1)
				(type default)
			)
			(layer "F.Fab")
		)
		(pad "1" smd circle
			(at -0.40005 0)
			(size 0 0)
			(layers "F.Cu" "F.Mask" "F.Paste")
			(net "P12V_SSD8")
		)
		(pad "2" smd circle
			(at 0.40005 0)
			(size 0 0)
			(layers "F.Cu" "F.Mask" "F.Paste")
			(net "GND")
		)
	)
	(footprint ""
		(layer "F.Cu")
		(at 90.028268 -300.64202 -90)
		(property "Reference" "R3882"
			(at 0 0 270)
			(layer "F.SilkS")
			(hide yes)
			(effects
				(font
					(size 1.27 1.27)
				)
			)
		)
		(property "Value" ""
			(at 0 0 270)
			(layer "F.Fab")
			(effects
				(font
					(size 1.27 1.27)
				)
			)
		)
		(duplicate_pad_numbers_are_jumpers no)
		(fp_line
			(start -0.7874 0.4064)
			(end -0.7874 -0.4064)
			(stroke
				(width 0.1524)
				(type default)
			)
			(layer "F.SilkS")
		)
		(fp_line
			(start 0.7874 0.4064)
			(end -0.7874 0.4064)
			(stroke
				(width 0.1524)
				(type default)
			)
			(layer "F.SilkS")
		)
		(fp_line
			(start -0.7874 -0.4064)
			(end 0.7874 -0.4064)
			(stroke
				(width 0.1524)
				(type default)
			)
			(layer "F.SilkS")
		)
		(fp_line
			(start 0.7874 -0.4064)
			(end 0.7874 0.4064)
			(stroke
				(width 0.1524)
				(type default)
			)
			(layer "F.SilkS")
		)
		(fp_line
			(start -0.67945 0.3048)
			(end -0.67945 -0.305054)
			(stroke
				(width 0.1)
				(type default)
			)
			(layer "F.Fab")
		)
		(fp_line
			(start -0.12065 0.3048)
			(end -0.67945 0.3048)
			(stroke
				(width 0.1)
				(type default)
			)
			(layer "F.Fab")
		)
		(fp_line
			(start 0.120396 0.3048)
			(end 0.120396 0.2794)
			(stroke
				(width 0.1)
				(type default)
			)
			(layer "F.Fab")
		)
		(fp_line
			(start 0.67945 0.3048)
			(end 0.120396 0.3048)
			(stroke
				(width 0.1)
				(type default)
			)
			(layer "F.Fab")
		)
		(fp_line
			(start -0.12065 0.2794)
			(end -0.12065 0.3048)
			(stroke
				(width 0.1)
				(type default)
			)
			(layer "F.Fab")
		)
		(fp_line
			(start 0.120396 0.2794)
			(end -0.12065 0.2794)
			(stroke
				(width 0.1)
				(type default)
			)
			(layer "F.Fab")
		)
		(fp_line
			(start -0.12065 -0.2794)
			(end 0.12065 -0.2794)
			(stroke
				(width 0.1)
				(type default)
			)
			(layer "F.Fab")
		)
		(fp_line
			(start 0.12065 -0.2794)
			(end 0.12065 -0.3048)
			(stroke
				(width 0.1)
				(type default)
			)
			(layer "F.Fab")
		)
		(fp_line
			(start 0.12065 -0.3048)
			(end 0.67945 -0.3048)
			(stroke
				(width 0.1)
				(type default)
			)
			(layer "F.Fab")
		)
		(fp_line
			(start 0.67945 -0.3048)
			(end 0.67945 0.3048)
			(stroke
				(width 0.1)
				(type default)
			)
			(layer "F.Fab")
		)
		(fp_line
			(start -0.67945 -0.305054)
			(end -0.12065 -0.305054)
			(stroke
				(width 0.1)
				(type default)
			)
			(layer "F.Fab")
		)
		(fp_line
			(start -0.12065 -0.305054)
			(end -0.12065 -0.2794)
			(stroke
				(width 0.1)
				(type default)
			)
			(layer "F.Fab")
		)
		(pad "1" smd circle
			(at -0.40005 0 270)
			(size 0 0)
			(layers "F.Cu" "F.Mask" "F.Paste")
			(net "I2C0_PEX0_SDA")
		)
		(pad "2" smd circle
			(at 0.40005 0 270)
			(size 0 0)
			(layers "F.Cu" "F.Mask" "F.Paste")
			(net "I2C_PEX0_HOST_SDA")
		)
	)
	(footprint ""
		(layer "F.Cu")
		(at 191.055752 -343.952322 90)
		(property "Reference" "C2539"
			(at 0 0 90)
			(layer "F.SilkS")
			(hide yes)
			(effects
				(font
					(size 1.27 1.27)
				)
			)
		)
		(property "Value" ""
			(at 0 0 90)
			(layer "F.Fab")
			(effects
				(font
					(size 1.27 1.27)
				)
			)
		)
		(duplicate_pad_numbers_are_jumpers no)
		(fp_line
			(start 0.299974 -0.150114)
			(end 0.299974 0.150114)
			(stroke
				(width 0.1)
				(type default)
			)
			(layer "F.Fab")
		)
		(fp_line
			(start -0.299974 -0.150114)
			(end 0.299974 -0.150114)
			(stroke
				(width 0.1)
				(type default)
			)
			(layer "F.Fab")
		)
		(fp_line
			(start 0.299974 0.150114)
			(end -0.299974 0.150114)
			(stroke
				(width 0.1)
				(type default)
			)
			(layer "F.Fab")
		)
		(fp_line
			(start -0.299974 0.150114)
			(end -0.299974 -0.150114)
			(stroke
				(width 0.1)
				(type default)
			)
			(layer "F.Fab")
		)
		(pad "1" smd rect
			(at -0.2667 0 90)
			(size 0.3048 0.381)
			(layers "F.Cu" "F.Mask" "F.Paste")
			(net "P5E_PEX1_STN4_TX_DN<66>")
		)
		(pad "2" smd rect
			(at 0.2667 0 90)
			(size 0.3048 0.381)
			(layers "F.Cu" "F.Mask" "F.Paste")
			(net "P5E_PEX1_STN4_TX_C_DN<66>")
		)
	)
	(footprint ""
		(layer "F.Cu")
		(at 213.838536 -44.341542 90)
		(property "Reference" "C320"
			(at 0 0 90)
			(layer "F.SilkS")
			(hide yes)
			(effects
				(font
					(size 1.27 1.27)
				)
			)
		)
		(property "Value" ""
			(at 0 0 90)
			(layer "F.Fab")
			(effects
				(font
					(size 1.27 1.27)
				)
			)
		)
		(duplicate_pad_numbers_are_jumpers no)
		(fp_line
			(start 0.7874 -0.4064)
			(end 0.7874 0.4064)
			(stroke
				(width 0.1524)
				(type default)
			)
			(layer "F.SilkS")
		)
		(fp_line
			(start -0.7874 -0.4064)
			(end 0.7874 -0.4064)
			(stroke
				(width 0.1524)
				(type default)
			)
			(layer "F.SilkS")
		)
		(fp_line
			(start 0.7874 0.4064)
			(end -0.7874 0.4064)
			(stroke
				(width 0.1524)
				(type default)
			)
			(layer "F.SilkS")
		)
		(fp_line
			(start -0.7874 0.4064)
			(end -0.7874 -0.4064)
			(stroke
				(width 0.1524)
				(type default)
			)
			(layer "F.SilkS")
		)
		(fp_line
			(start -0.12065 -0.305054)
			(end -0.12065 -0.2794)
			(stroke
				(width 0.1)
				(type default)
			)
			(layer "F.Fab")
		)
		(fp_line
			(start -0.67945 -0.305054)
			(end -0.12065 -0.305054)
			(stroke
				(width 0.1)
				(type default)
			)
			(layer "F.Fab")
		)
		(fp_line
			(start 0.67945 -0.3048)
			(end 0.67945 0.3048)
			(stroke
				(width 0.1)
				(type default)
			)
			(layer "F.Fab")
		)
		(fp_line
			(start 0.12065 -0.3048)
			(end 0.67945 -0.3048)
			(stroke
				(width 0.1)
				(type default)
			)
			(layer "F.Fab")
		)
		(fp_line
			(start 0.12065 -0.2794)
			(end 0.12065 -0.3048)
			(stroke
				(width 0.1)
				(type default)
			)
			(layer "F.Fab")
		)
		(fp_line
			(start -0.12065 -0.2794)
			(end 0.12065 -0.2794)
			(stroke
				(width 0.1)
				(type default)
			)
			(layer "F.Fab")
		)
		(fp_line
			(start 0.120396 0.2794)
			(end -0.12065 0.2794)
			(stroke
				(width 0.1)
				(type default)
			)
			(layer "F.Fab")
		)
		(fp_line
			(start -0.12065 0.2794)
			(end -0.12065 0.3048)
			(stroke
				(width 0.1)
				(type default)
			)
			(layer "F.Fab")
		)
		(fp_line
			(start 0.67945 0.3048)
			(end 0.120396 0.3048)
			(stroke
				(width 0.1)
				(type default)
			)
			(layer "F.Fab")
		)
		(fp_line
			(start 0.120396 0.3048)
			(end 0.120396 0.2794)
			(stroke
				(width 0.1)
				(type default)
			)
			(layer "F.Fab")
		)
		(fp_line
			(start -0.12065 0.3048)
			(end -0.67945 0.3048)
			(stroke
				(width 0.1)
				(type default)
			)
			(layer "F.Fab")
		)
		(fp_line
			(start -0.67945 0.3048)
			(end -0.67945 -0.305054)
			(stroke
				(width 0.1)
				(type default)
			)
			(layer "F.Fab")
		)
		(pad "1" smd circle
			(at -0.40005 0 90)
			(size 0 0)
			(layers "F.Cu" "F.Mask" "F.Paste")
			(net "P12V_SSD7_VIN_P")
		)
		(pad "2" smd circle
			(at 0.40005 0 90)
			(size 0 0)
			(layers "F.Cu" "F.Mask" "F.Paste")
			(net "P12V_SSD7_VIN_N")
		)
	)
)
